# T6G (Grand Teton) — schematic netlist excerpt (pin names and nets, part order shuffled) for the footprints in the layout excerpt that follows; sources: Cadence DE-HDL packaged netlist, KiCad conversion of 04192023_DAF0TMB3IC0_F0TG_MB_C_brd_V02_OCP.brd

PR341  Q_RES  0 5% EMPTY  pkg 0402LF  page 218 : A = PVDDCR_CPU1_P1_PVCC ; B = P3V3_AUX
R3516  Q_RES  0 5% CHIP  pkg 0402LF  page 245 : A = GPU_BASE_ID0 ; B = GPU_BASE_ID0_R

(kicad_pcb
	(version 20260206)
	(generator "pcbnew")
	(generator_version "10.0")
	(general
		(thickness 1.6)
		(legacy_teardrops no)
	)
	(paper "A4")
	(title_block
		(title "04192023_DAF0TMB3IC0_F0TG_MB_C_brd_V02_OCP.brd")
		(comment 1 "Grand Teton / footprints 974-975 of 8354")
	)
	(layers
		(0 "F.Cu" signal "TOP")
		(4 "In1.Cu" signal "GND")
		(6 "In2.Cu" signal "IN1")
		(8 "In3.Cu" signal "GND1")
		(10 "In4.Cu" signal "IN2")
		(12 "In5.Cu" signal "GND2")
		(14 "In6.Cu" signal "IN3")
		(16 "In7.Cu" signal "GND3")
		(18 "In8.Cu" signal "VCC")
		(20 "In9.Cu" signal "VCC1")
		(22 "In10.Cu" signal "GND4")
		(24 "In11.Cu" signal "IN4")
		(26 "In12.Cu" signal "GND5")
		(28 "In13.Cu" signal "IN5")
		(30 "In14.Cu" signal "GND6")
		(32 "In15.Cu" signal "IN6")
		(34 "In16.Cu" signal "GND7")
		(2 "B.Cu" signal "BOTTOM")
		(9 "F.Adhes" user "F.Adhesive")
		(11 "B.Adhes" user "B.Adhesive")
		(13 "F.Paste" user "Package Geometry/Pastemask Top")
		(15 "B.Paste" user "Package Geometry/Pastemask Bottom")
		(5 "F.SilkS" user "Ref Des/Silkscreen Top")
		(7 "B.SilkS" user "Ref Des/Silkscreen Bottom")
		(1 "F.Mask" user "Board Geometry/Soldermask Top")
		(3 "B.Mask" user "Board Geometry/Soldermask Bottom")
		(17 "Dwgs.User" user "User.Drawings")
		(19 "Cmts.User" user "User.Comments")
		(21 "Eco1.User" user "User.Eco1")
		(23 "Eco2.User" user "User.Eco2")
		(25 "Edge.Cuts" user "Board Geometry/Outline")
		(27 "Margin" user)
		(31 "F.CrtYd" user "Package Geometry/Place Bound Top")
		(29 "B.CrtYd" user "Package Geometry/Place Bound Bottom")
		(35 "F.Fab" user "Ref Des/Assembly Top")
		(33 "B.Fab" user "Ref Des/Assembly Bottom")
	)
	(footprint ""
		(layer "F.Cu")
		(at 23.012654 -351.609406 90)
		(property "Reference" "PR341"
			(at 0 0 90)
			(layer "F.SilkS")
			(hide yes)
			(effects
				(font
					(size 1.27 1.27)
				)
			)
		)
		(property "Value" ""
			(at 0 0 90)
			(layer "F.Fab")
			(effects
				(font
					(size 1.27 1.27)
				)
			)
		)
		(duplicate_pad_numbers_are_jumpers no)
		(fp_line
			(start 0.7874 -0.4064)
			(end 0.7874 0.4064)
			(stroke
				(width 0.1524)
				(type default)
			)
			(layer "F.SilkS")
		)
		(fp_line
			(start -0.7874 -0.4064)
			(end 0.7874 -0.4064)
			(stroke
				(width 0.1524)
				(type default)
			)
			(layer "F.SilkS")
		)
		(fp_line
			(start 0.7874 0.4064)
			(end -0.7874 0.4064)
			(stroke
				(width 0.1524)
				(type default)
			)
			(layer "F.SilkS")
		)
		(fp_line
			(start -0.7874 0.4064)
			(end -0.7874 -0.4064)
			(stroke
				(width 0.1524)
				(type default)
			)
			(layer "F.SilkS")
		)
		(fp_line
			(start -0.12065 -0.305054)
			(end -0.12065 -0.2794)
			(stroke
				(width 0.1)
				(type default)
			)
			(layer "F.Fab")
		)
		(fp_line
			(start -0.67945 -0.305054)
			(end -0.12065 -0.305054)
			(stroke
				(width 0.1)
				(type default)
			)
			(layer "F.Fab")
		)
		(fp_line
			(start 0.67945 -0.3048)
			(end 0.67945 0.3048)
			(stroke
				(width 0.1)
				(type default)
			)
			(layer "F.Fab")
		)
		(fp_line
			(start 0.12065 -0.3048)
			(end 0.67945 -0.3048)
			(stroke
				(width 0.1)
				(type default)
			)
			(layer "F.Fab")
		)
		(fp_line
			(start 0.12065 -0.2794)
			(end 0.12065 -0.3048)
			(stroke
				(width 0.1)
				(type default)
			)
			(layer "F.Fab")
		)
		(fp_line
			(start -0.12065 -0.2794)
			(end 0.12065 -0.2794)
			(stroke
				(width 0.1)
				(type default)
			)
			(layer "F.Fab")
		)
		(fp_line
			(start 0.120396 0.2794)
			(end -0.12065 0.2794)
			(stroke
				(width 0.1)
				(type default)
			)
			(layer "F.Fab")
		)
		(fp_line
			(start -0.12065 0.2794)
			(end -0.12065 0.3048)
			(stroke
				(width 0.1)
				(type default)
			)
			(layer "F.Fab")
		)
		(fp_line
			(start 0.67945 0.3048)
			(end 0.120396 0.3048)
			(stroke
				(width 0.1)
				(type default)
			)
			(layer "F.Fab")
		)
		(fp_line
			(start 0.120396 0.3048)
			(end 0.120396 0.2794)
			(stroke
				(width 0.1)
				(type default)
			)
			(layer "F.Fab")
		)
		(fp_line
			(start -0.12065 0.3048)
			(end -0.67945 0.3048)
			(stroke
				(width 0.1)
				(type default)
			)
			(layer "F.Fab")
		)
		(fp_line
			(start -0.67945 0.3048)
			(end -0.67945 -0.305054)
			(stroke
				(width 0.1)
				(type default)
			)
			(layer "F.Fab")
		)
		(pad "1" smd circle
			(at -0.40005 0 90)
			(size 0 0)
			(layers "F.Cu" "F.Mask" "F.Paste")
			(net "PVDDCR_CPU1_P1_PVCC")
		)
		(pad "2" smd circle
			(at 0.40005 0 90)
			(size 0 0)
			(layers "F.Cu" "F.Mask" "F.Paste")
			(net "P3V3_AUX")
		)
	)
	(footprint ""
		(layer "F.Cu")
		(at 188.296804 -426.353478 -90)
		(property "Reference" "R3516"
			(at 0 0 270)
			(layer "F.SilkS")
			(hide yes)
			(effects
				(font
					(size 1.27 1.27)
				)
			)
		)
		(property "Value" ""
			(at 0 0 270)
			(layer "F.Fab")
			(effects
				(font
					(size 1.27 1.27)
				)
			)
		)
		(duplicate_pad_numbers_are_jumpers no)
		(fp_line
			(start -0.7874 0.4064)
			(end -0.7874 -0.4064)
			(stroke
				(width 0.1524)
				(type default)
			)
			(layer "F.SilkS")
		)
		(fp_line
			(start 0.7874 0.4064)
			(end -0.7874 0.4064)
			(stroke
				(width 0.1524)
				(type default)
			)
			(layer "F.SilkS")
		)
		(fp_line
			(start -0.7874 -0.4064)
			(end 0.7874 -0.4064)
			(stroke
				(width 0.1524)
				(type default)
			)
			(layer "F.SilkS")
		)
		(fp_line
			(start 0.7874 -0.4064)
			(end 0.7874 0.4064)
			(stroke
				(width 0.1524)
				(type default)
			)
			(layer "F.SilkS")
		)
		(fp_line
			(start -0.67945 0.3048)
			(end -0.67945 -0.305054)
			(stroke
				(width 0.1)
				(type default)
			)
			(layer "F.Fab")
		)
		(fp_line
			(start -0.12065 0.3048)
			(end -0.67945 0.3048)
			(stroke
				(width 0.1)
				(type default)
			)
			(layer "F.Fab")
		)
		(fp_line
			(start 0.120396 0.3048)
			(end 0.120396 0.2794)
			(stroke
				(width 0.1)
				(type default)
			)
			(layer "F.Fab")
		)
		(fp_line
			(start 0.67945 0.3048)
			(end 0.120396 0.3048)
			(stroke
				(width 0.1)
				(type default)
			)
			(layer "F.Fab")
		)
		(fp_line
			(start -0.12065 0.2794)
			(end -0.12065 0.3048)
			(stroke
				(width 0.1)
				(type default)
			)
			(layer "F.Fab")
		)
		(fp_line
			(start 0.120396 0.2794)
			(end -0.12065 0.2794)
			(stroke
				(width 0.1)
				(type default)
			)
			(layer "F.Fab")
		)
		(fp_line
			(start -0.12065 -0.2794)
			(end 0.12065 -0.2794)
			(stroke
				(width 0.1)
				(type default)
			)
			(layer "F.Fab")
		)
		(fp_line
			(start 0.12065 -0.2794)
			(end 0.12065 -0.3048)
			(stroke
				(width 0.1)
				(type default)
			)
			(layer "F.Fab")
		)
		(fp_line
			(start 0.12065 -0.3048)
			(end 0.67945 -0.3048)
			(stroke
				(width 0.1)
				(type default)
			)
			(layer "F.Fab")
		)
		(fp_line
			(start 0.67945 -0.3048)
			(end 0.67945 0.3048)
			(stroke
				(width 0.1)
				(type default)
			)
			(layer "F.Fab")
		)
		(fp_line
			(start -0.67945 -0.305054)
			(end -0.12065 -0.305054)
			(stroke
				(width 0.1)
				(type default)
			)
			(layer "F.Fab")
		)
		(fp_line
			(start -0.12065 -0.305054)
			(end -0.12065 -0.2794)
			(stroke
				(width 0.1)
				(type default)
			)
			(layer "F.Fab")
		)
		(pad "1" smd circle
			(at -0.40005 0 270)
			(size 0 0)
			(layers "F.Cu" "F.Mask" "F.Paste")
			(net "GPU_BASE_ID0")
		)
		(pad "2" smd circle
			(at 0.40005 0 270)
			(size 0 0)
			(layers "F.Cu" "F.Mask" "F.Paste")
			(net "GPU_BASE_ID0_R")
		)
	)
)
